(kicad_pcb
	(version 20260206)
	(generator "pcbnew")
	(generator_version "10.0")
	(general
		(thickness 1.6)
		(legacy_teardrops no)
	)
	(paper "A4")
	(title_block
		(title "04192023_DAF0TMB3IC0_F0TG_MB_C_brd_V02_OCP.brd")
		(comment 1 "Grand Teton / footprints 947-952 of 8354")
	)
	(layers
		(0 "F.Cu" signal "TOP")
		(4 "In1.Cu" signal "GND")
		(6 "In2.Cu" signal "IN1")
		(8 "In3.Cu" signal "GND1")
		(10 "In4.Cu" signal "IN2")
		(12 "In5.Cu" signal "GND2")
		(14 "In6.Cu" signal "IN3")
		(16 "In7.Cu" signal "GND3")
		(18 "In8.Cu" signal "VCC")
		(20 "In9.Cu" signal "VCC1")
		(22 "In10.Cu" signal "GND4")
		(24 "In11.Cu" signal "IN4")
		(26 "In12.Cu" signal "GND5")
		(28 "In13.Cu" signal "IN5")
		(30 "In14.Cu" signal "GND6")
		(32 "In15.Cu" signal "IN6")
		(34 "In16.Cu" signal "GND7")
		(2 "B.Cu" signal "BOTTOM")
		(9 "F.Adhes" user "F.Adhesive")
		(11 "B.Adhes" user "B.Adhesive")
		(13 "F.Paste" user "Package Geometry/Pastemask Top")
		(15 "B.Paste" user "Package Geometry/Pastemask Bottom")
		(5 "F.SilkS" user "Ref Des/Silkscreen Top")
		(7 "B.SilkS" user "Ref Des/Silkscreen Bottom")
		(1 "F.Mask" user "Board Geometry/Soldermask Top")
		(3 "B.Mask" user "Board Geometry/Soldermask Bottom")
		(17 "Dwgs.User" user "User.Drawings")
		(19 "Cmts.User" user "User.Comments")
		(21 "Eco1.User" user "User.Eco1")
		(23 "Eco2.User" user "User.Eco2")
		(25 "Edge.Cuts" user "Board Geometry/Outline")
		(27 "Margin" user)
		(31 "F.CrtYd" user "Package Geometry/Place Bound Top")
		(29 "B.CrtYd" user "Package Geometry/Place Bound Bottom")
		(35 "F.Fab" user "Ref Des/Assembly Top")
		(33 "B.Fab" user "Ref Des/Assembly Bottom")
	)
	(footprint ""
		(layer "F.Cu")
		(at 88.06053 -59.83097 -90)
		(property "Reference" "R3832"
			(at 0 0 270)
			(layer "F.SilkS")
			(hide yes)
			(effects
				(font
					(size 1.27 1.27)
				)
			)
		)
		(property "Value" ""
			(at 0 0 270)
			(layer "F.Fab")
			(effects
				(font
					(size 1.27 1.27)
				)
			)
		)
		(duplicate_pad_numbers_are_jumpers no)
		(fp_line
			(start -0.7874 0.4064)
			(end -0.7874 -0.4064)
			(stroke
				(width 0.1524)
				(type default)
			)
			(layer "F.SilkS")
		)
		(fp_line
			(start 0.7874 0.4064)
			(end -0.7874 0.4064)
			(stroke
				(width 0.1524)
				(type default)
			)
			(layer "F.SilkS")
		)
		(fp_line
			(start -0.7874 -0.4064)
			(end 0.7874 -0.4064)
			(stroke
				(width 0.1524)
				(type default)
			)
			(layer "F.SilkS")
		)
		(fp_line
			(start 0.7874 -0.4064)
			(end 0.7874 0.4064)
			(stroke
				(width 0.1524)
				(type default)
			)
			(layer "F.SilkS")
		)
		(fp_line
			(start -0.67945 0.3048)
			(end -0.67945 -0.305054)
			(stroke
				(width 0.1)
				(type default)
			)
			(layer "F.Fab")
		)
		(fp_line
			(start -0.12065 0.3048)
			(end -0.67945 0.3048)
			(stroke
				(width 0.1)
				(type default)
			)
			(layer "F.Fab")
		)
		(fp_line
			(start 0.120396 0.3048)
			(end 0.120396 0.2794)
			(stroke
				(width 0.1)
				(type default)
			)
			(layer "F.Fab")
		)
		(fp_line
			(start 0.67945 0.3048)
			(end 0.120396 0.3048)
			(stroke
				(width 0.1)
				(type default)
			)
			(layer "F.Fab")
		)
		(fp_line
			(start -0.12065 0.2794)
			(end -0.12065 0.3048)
			(stroke
				(width 0.1)
				(type default)
			)
			(layer "F.Fab")
		)
		(fp_line
			(start 0.120396 0.2794)
			(end -0.12065 0.2794)
			(stroke
				(width 0.1)
				(type default)
			)
			(layer "F.Fab")
		)
		(fp_line
			(start -0.12065 -0.2794)
			(end 0.12065 -0.2794)
			(stroke
				(width 0.1)
				(type default)
			)
			(layer "F.Fab")
		)
		(fp_line
			(start 0.12065 -0.2794)
			(end 0.12065 -0.3048)
			(stroke
				(width 0.1)
				(type default)
			)
			(layer "F.Fab")
		)
		(fp_line
			(start 0.12065 -0.3048)
			(end 0.67945 -0.3048)
			(stroke
				(width 0.1)
				(type default)
			)
			(layer "F.Fab")
		)
		(fp_line
			(start 0.67945 -0.3048)
			(end 0.67945 0.3048)
			(stroke
				(width 0.1)
				(type default)
			)
			(layer "F.Fab")
		)
		(fp_line
			(start -0.67945 -0.305054)
			(end -0.12065 -0.305054)
			(stroke
				(width 0.1)
				(type default)
			)
			(layer "F.Fab")
		)
		(fp_line
			(start -0.12065 -0.305054)
			(end -0.12065 -0.2794)
			(stroke
				(width 0.1)
				(type default)
			)
			(layer "F.Fab")
		)
		(pad "1" smd circle
			(at -0.40005 0 270)
			(size 0 0)
			(layers "F.Cu" "F.Mask" "F.Paste")
			(net "P3V3_OCP_PWRGD_2")
		)
		(pad "2" smd circle
			(at 0.40005 0 270)
			(size 0 0)
			(layers "F.Cu" "F.Mask" "F.Paste")
			(net "OCP_V3_2_P3V3_PWRGD")
		)
	)
	(footprint ""
		(layer "F.Cu")
		(at 223.37141 -73.517506)
		(property "Reference" "PC2216"
			(at 0 0 0)
			(layer "F.SilkS")
			(hide yes)
			(effects
				(font
					(size 1.27 1.27)
				)
			)
		)
		(property "Value" ""
			(at 0 0 0)
			(layer "F.Fab")
			(effects
				(font
					(size 1.27 1.27)
				)
			)
		)
		(duplicate_pad_numbers_are_jumpers no)
		(fp_line
			(start -0.7874 -0.4064)
			(end 0.7874 -0.4064)
			(stroke
				(width 0.1524)
				(type default)
			)
			(layer "F.SilkS")
		)
		(fp_line
			(start -0.7874 0.4064)
			(end -0.7874 -0.4064)
			(stroke
				(width 0.1524)
				(type default)
			)
			(layer "F.SilkS")
		)
		(fp_line
			(start 0.7874 -0.4064)
			(end 0.7874 0.4064)
			(stroke
				(width 0.1524)
				(type default)
			)
			(layer "F.SilkS")
		)
		(fp_line
			(start 0.7874 0.4064)
			(end -0.7874 0.4064)
			(stroke
				(width 0.1524)
				(type default)
			)
			(layer "F.SilkS")
		)
		(fp_line
			(start -0.67945 -0.305054)
			(end -0.12065 -0.305054)
			(stroke
				(width 0.1)
				(type default)
			)
			(layer "F.Fab")
		)
		(fp_line
			(start -0.67945 0.3048)
			(end -0.67945 -0.305054)
			(stroke
				(width 0.1)
				(type default)
			)
			(layer "F.Fab")
		)
		(fp_line
			(start -0.12065 -0.305054)
			(end -0.12065 -0.2794)
			(stroke
				(width 0.1)
				(type default)
			)
			(layer "F.Fab")
		)
		(fp_line
			(start -0.12065 -0.2794)
			(end 0.12065 -0.2794)
			(stroke
				(width 0.1)
				(type default)
			)
			(layer "F.Fab")
		)
		(fp_line
			(start -0.12065 0.2794)
			(end -0.12065 0.3048)
			(stroke
				(width 0.1)
				(type default)
			)
			(layer "F.Fab")
		)
		(fp_line
			(start -0.12065 0.3048)
			(end -0.67945 0.3048)
			(stroke
				(width 0.1)
				(type default)
			)
			(layer "F.Fab")
		)
		(fp_line
			(start 0.120396 0.2794)
			(end -0.12065 0.2794)
			(stroke
				(width 0.1)
				(type default)
			)
			(layer "F.Fab")
		)
		(fp_line
			(start 0.120396 0.3048)
			(end 0.120396 0.2794)
			(stroke
				(width 0.1)
				(type default)
			)
			(layer "F.Fab")
		)
		(fp_line
			(start 0.12065 -0.3048)
			(end 0.67945 -0.3048)
			(stroke
				(width 0.1)
				(type default)
			)
			(layer "F.Fab")
		)
		(fp_line
			(start 0.12065 -0.2794)
			(end 0.12065 -0.3048)
			(stroke
				(width 0.1)
				(type default)
			)
			(layer "F.Fab")
		)
		(fp_line
			(start 0.67945 -0.3048)
			(end 0.67945 0.3048)
			(stroke
				(width 0.1)
				(type default)
			)
			(layer "F.Fab")
		)
		(fp_line
			(start 0.67945 0.3048)
			(end 0.120396 0.3048)
			(stroke
				(width 0.1)
				(type default)
			)
			(layer "F.Fab")
		)
		(pad "1" smd circle
			(at -0.40005 0)
			(size 0 0)
			(layers "F.Cu" "F.Mask" "F.Paste")
			(net "P3V3_E1S_GATE_0")
		)
		(pad "2" smd circle
			(at 0.40005 0)
			(size 0 0)
			(layers "F.Cu" "F.Mask" "F.Paste")
			(net "GND")
		)
	)
	(footprint ""
		(layer "F.Cu")
		(at 13.12672 -74.719688)
		(property "Reference" "U242"
			(at 1.629156 2.268982 0)
			(unlocked yes)
			(layer "F.SilkS")
			(effects
				(font
					(size 0.7874 0.5842)
					(thickness 0.1524)
				)
				(justify left)
			)
		)
		(property "Value" ""
			(at 0 0 0)
			(layer "F.Fab")
			(effects
				(font
					(size 1.27 1.27)
				)
			)
		)
		(duplicate_pad_numbers_are_jumpers no)
		(fp_line
			(start -1.207008 -1.549908)
			(end -1.207008 1.549908)
			(stroke
				(width 0.1524)
				(type default)
			)
			(layer "F.SilkS")
		)
		(fp_line
			(start -1.207008 1.549908)
			(end 1.207008 1.549908)
			(stroke
				(width 0.1524)
				(type default)
			)
			(layer "F.SilkS")
		)
		(fp_line
			(start -0.762508 -1.549908)
			(end -1.207008 -1.549908)
			(stroke
				(width 0.1524)
				(type default)
			)
			(layer "F.SilkS")
		)
		(fp_line
			(start 0 -0.635)
			(end -0.762508 -1.549908)
			(stroke
				(width 0.1524)
				(type default)
			)
			(layer "F.SilkS")
		)
		(fp_line
			(start 0.762508 -1.549908)
			(end 0 -0.635)
			(stroke
				(width 0.1524)
				(type default)
			)
			(layer "F.SilkS")
		)
		(fp_line
			(start 1.207008 -1.549908)
			(end 0.762508 -1.549908)
			(stroke
				(width 0.1524)
				(type default)
			)
			(layer "F.SilkS")
		)
		(fp_line
			(start 1.207008 1.549908)
			(end 1.207008 -1.549908)
			(stroke
				(width 0.1524)
				(type default)
			)
			(layer "F.SilkS")
		)
		(fp_poly
			(pts
				(xy -2.608326 -0.655828) (xy -3.524758 0.015494) (xy -3.695192 -0.986028)
			)
			(stroke
				(width 0)
				(type default)
			)
			(fill yes)
			(layer "F.SilkS")
		)
		(fp_line
			(start -1.549908 -1.549908)
			(end -1.549908 1.549908)
			(stroke
				(width 0.1)
				(type default)
			)
			(layer "F.Fab")
		)
		(fp_line
			(start -1.549908 1.549908)
			(end 1.549908 1.549908)
			(stroke
				(width 0.1)
				(type default)
			)
			(layer "F.Fab")
		)
		(fp_line
			(start 1.549908 -1.549908)
			(end -1.549908 -1.549908)
			(stroke
				(width 0.1)
				(type default)
			)
			(layer "F.Fab")
		)
		(fp_line
			(start 1.549908 1.549908)
			(end 1.549908 -1.549908)
			(stroke
				(width 0.1)
				(type default)
			)
			(layer "F.Fab")
		)
		(fp_poly
			(pts
				(xy -3.4036 -1.53289) (xy -3.4036 -0.51689) (xy -2.3876 -1.02489)
			)
			(stroke
				(width 0)
				(type default)
			)
			(fill yes)
			(layer "F.Fab")
		)
		(pad "1" smd rect
			(at -1.774952 -1.02489 270)
			(size 0.508 0.8636)
			(layers "F.Cu" "F.Mask" "F.Paste")
			(net "OCP_SFF_PRSNT01_R1_N")
		)
		(pad "2" smd rect
			(at -1.774952 -0.32512 270)
			(size 0.4064 0.8636)
			(layers "F.Cu" "F.Mask" "F.Paste")
			(net "OCP_SFF_PRSNT23_R1_N")
		)
		(pad "3" smd rect
			(at -1.774952 0.32512 270)
			(size 0.4064 0.8636)
			(layers "F.Cu" "F.Mask" "F.Paste")
			(net "OCP_V3_2_PRSNT_ALL_R_N")
		)
		(pad "4" smd rect
			(at -1.774952 1.02489 270)
			(size 0.508 0.8636)
			(layers "F.Cu" "F.Mask" "F.Paste")
			(net "GND")
		)
		(pad "5" smd rect
			(at 1.774952 1.02489 270)
			(size 0.508 0.8636)
			(layers "F.Cu" "F.Mask" "F.Paste")
			(net "OCP_V3_2_PRSNT01_R1_N")
		)
		(pad "6" smd rect
			(at 1.774952 0.32512 270)
			(size 0.4064 0.8636)
			(layers "F.Cu" "F.Mask" "F.Paste")
			(net "OCP_V3_2_PRSNT23_R1_N")
		)
		(pad "7" smd rect
			(at 1.774952 -0.32512 270)
			(size 0.4064 0.8636)
			(layers "F.Cu" "F.Mask" "F.Paste")
			(net "OCP_SFF_PRSNT_ALL_R_N")
		)
		(pad "8" smd rect
			(at 1.774952 -1.02489 270)
			(size 0.508 0.8636)
			(layers "F.Cu" "F.Mask" "F.Paste")
			(net "P3V3_AUX")
		)
	)
	(footprint ""
		(layer "F.Cu")
		(at 283.21127 -401.586954 90)
		(property "Reference" "R353"
			(at 0 0 90)
			(layer "F.SilkS")
			(hide yes)
			(effects
				(font
					(size 1.27 1.27)
				)
			)
		)
		(property "Value" ""
			(at 0 0 90)
			(layer "F.Fab")
			(effects
				(font
					(size 1.27 1.27)
				)
			)
		)
		(duplicate_pad_numbers_are_jumpers no)
		(fp_line
			(start 0.7874 -0.4064)
			(end 0.7874 0.4064)
			(stroke
				(width 0.1524)
				(type default)
			)
			(layer "F.SilkS")
		)
		(fp_line
			(start -0.7874 -0.4064)
			(end 0.7874 -0.4064)
			(stroke
				(width 0.1524)
				(type default)
			)
			(layer "F.SilkS")
		)
		(fp_line
			(start 0.7874 0.4064)
			(end -0.7874 0.4064)
			(stroke
				(width 0.1524)
				(type default)
			)
			(layer "F.SilkS")
		)
		(fp_line
			(start -0.7874 0.4064)
			(end -0.7874 -0.4064)
			(stroke
				(width 0.1524)
				(type default)
			)
			(layer "F.SilkS")
		)
		(fp_line
			(start -0.12065 -0.305054)
			(end -0.12065 -0.2794)
			(stroke
				(width 0.1)
				(type default)
			)
			(layer "F.Fab")
		)
		(fp_line
			(start -0.67945 -0.305054)
			(end -0.12065 -0.305054)
			(stroke
				(width 0.1)
				(type default)
			)
			(layer "F.Fab")
		)
		(fp_line
			(start 0.67945 -0.3048)
			(end 0.67945 0.3048)
			(stroke
				(width 0.1)
				(type default)
			)
			(layer "F.Fab")
		)
		(fp_line
			(start 0.12065 -0.3048)
			(end 0.67945 -0.3048)
			(stroke
				(width 0.1)
				(type default)
			)
			(layer "F.Fab")
		)
		(fp_line
			(start 0.12065 -0.2794)
			(end 0.12065 -0.3048)
			(stroke
				(width 0.1)
				(type default)
			)
			(layer "F.Fab")
		)
		(fp_line
			(start -0.12065 -0.2794)
			(end 0.12065 -0.2794)
			(stroke
				(width 0.1)
				(type default)
			)
			(layer "F.Fab")
		)
		(fp_line
			(start 0.120396 0.2794)
			(end -0.12065 0.2794)
			(stroke
				(width 0.1)
				(type default)
			)
			(layer "F.Fab")
		)
		(fp_line
			(start -0.12065 0.2794)
			(end -0.12065 0.3048)
			(stroke
				(width 0.1)
				(type default)
			)
			(layer "F.Fab")
		)
		(fp_line
			(start 0.67945 0.3048)
			(end 0.120396 0.3048)
			(stroke
				(width 0.1)
				(type default)
			)
			(layer "F.Fab")
		)
		(fp_line
			(start 0.120396 0.3048)
			(end 0.120396 0.2794)
			(stroke
				(width 0.1)
				(type default)
			)
			(layer "F.Fab")
		)
		(fp_line
			(start -0.12065 0.3048)
			(end -0.67945 0.3048)
			(stroke
				(width 0.1)
				(type default)
			)
			(layer "F.Fab")
		)
		(fp_line
			(start -0.67945 0.3048)
			(end -0.67945 -0.305054)
			(stroke
				(width 0.1)
				(type default)
			)
			(layer "F.Fab")
		)
		(pad "1" smd circle
			(at -0.40005 0 90)
			(size 0 0)
			(layers "F.Cu" "F.Mask" "F.Paste")
			(net "P12V_HSC_T_CRIT_N")
		)
		(pad "2" smd circle
			(at 0.40005 0 90)
			(size 0 0)
			(layers "F.Cu" "F.Mask" "F.Paste")
			(net "P12V_HSC_T_CRIT_R_N")
		)
	)
	(footprint ""
		(layer "F.Cu")
		(at 427.269656 -397.135604 180)
		(property "Reference" "L29"
			(at 0 0 180)
			(layer "F.SilkS")
			(hide yes)
			(effects
				(font
					(size 1.27 1.27)
				)
			)
		)
		(property "Value" ""
			(at 0 0 180)
			(layer "F.Fab")
			(effects
				(font
					(size 1.27 1.27)
				)
			)
		)
		(duplicate_pad_numbers_are_jumpers no)
		(fp_line
			(start 0.762 0.381)
			(end -0.762 0.381)
			(stroke
				(width 0.1524)
				(type default)
			)
			(layer "F.SilkS")
		)
		(fp_line
			(start 0.762 -0.381)
			(end 0.762 0.381)
			(stroke
				(width 0.1524)
				(type default)
			)
			(layer "F.SilkS")
		)
		(fp_line
			(start -0.762 0.381)
			(end -0.762 -0.381)
			(stroke
				(width 0.1524)
				(type default)
			)
			(layer "F.SilkS")
		)
		(fp_line
			(start -0.762 -0.381)
			(end 0.762 -0.381)
			(stroke
				(width 0.1524)
				(type default)
			)
			(layer "F.SilkS")
		)
		(fp_line
			(start 0.680466 0.306324)
			(end 0.118364 0.306324)
			(stroke
				(width 0.1)
				(type default)
			)
			(layer "F.Fab")
		)
		(fp_line
			(start 0.680466 -0.306324)
			(end 0.680466 0.306324)
			(stroke
				(width 0.1)
				(type default)
			)
			(layer "F.Fab")
		)
		(fp_line
			(start 0.118872 -0.2794)
			(end 0.118872 -0.306324)
			(stroke
				(width 0.1)
				(type default)
			)
			(layer "F.Fab")
		)
		(fp_line
			(start 0.118872 -0.306324)
			(end 0.680466 -0.306324)
			(stroke
				(width 0.1)
				(type default)
			)
			(layer "F.Fab")
		)
		(fp_line
			(start 0.118364 0.306324)
			(end 0.118364 0.2794)
			(stroke
				(width 0.1)
				(type default)
			)
			(layer "F.Fab")
		)
		(fp_line
			(start 0.118364 0.2794)
			(end -0.119634 0.2794)
			(stroke
				(width 0.1)
				(type default)
			)
			(layer "F.Fab")
		)
		(fp_line
			(start -0.118364 -0.2794)
			(end 0.118872 -0.2794)
			(stroke
				(width 0.1)
				(type default)
			)
			(layer "F.Fab")
		)
		(fp_line
			(start -0.118364 -0.307086)
			(end -0.118364 -0.2794)
			(stroke
				(width 0.1)
				(type default)
			)
			(layer "F.Fab")
		)
		(fp_line
			(start -0.119634 0.30607)
			(end -0.681736 0.30607)
			(stroke
				(width 0.1)
				(type default)
			)
			(layer "F.Fab")
		)
		(fp_line
			(start -0.119634 0.2794)
			(end -0.119634 0.30607)
			(stroke
				(width 0.1)
				(type default)
			)
			(layer "F.Fab")
		)
		(fp_line
			(start -0.681736 0.30607)
			(end -0.681736 -0.307086)
			(stroke
				(width 0.1)
				(type default)
			)
			(layer "F.Fab")
		)
		(fp_line
			(start -0.681736 -0.307086)
			(end -0.118364 -0.307086)
			(stroke
				(width 0.1)
				(type default)
			)
			(layer "F.Fab")
		)
		(pad "1" smd rect
			(at -0.40005 0)
			(size 0.4572 0.508)
			(layers "F.Cu" "F.Mask" "F.Paste")
			(net "P1V8_CPU0_RT_1D")
		)
		(pad "2" smd rect
			(at 0.40005 0)
			(size 0.4572 0.508)
			(layers "F.Cu" "F.Mask" "F.Paste")
			(net "P1V8_CPU0_RT2_1A_1D")
		)
	)
	(footprint ""
		(layer "F.Cu")
		(at 100.48367 -406.151588 180)
		(property "Reference" "R593"
			(at 0 0 180)
			(layer "F.SilkS")
			(hide yes)
			(effects
				(font
					(size 1.27 1.27)
				)
			)
		)
		(property "Value" ""
			(at 0 0 180)
			(layer "F.Fab")
			(effects
				(font
					(size 1.27 1.27)
				)
			)
		)
		(duplicate_pad_numbers_are_jumpers no)
		(fp_line
			(start 0.7874 0.4064)
			(end -0.7874 0.4064)
			(stroke
				(width 0.1524)
				(type default)
			)
			(layer "F.SilkS")
		)
		(fp_line
			(start 0.7874 -0.4064)
			(end 0.7874 0.4064)
			(stroke
				(width 0.1524)
				(type default)
			)
			(layer "F.SilkS")
		)
		(fp_line
			(start -0.7874 0.4064)
			(end -0.7874 -0.4064)
			(stroke
				(width 0.1524)
				(type default)
			)
			(layer "F.SilkS")
		)
		(fp_line
			(start -0.7874 -0.4064)
			(end 0.7874 -0.4064)
			(stroke
				(width 0.1524)
				(type default)
			)
			(layer "F.SilkS")
		)
		(fp_line
			(start 0.67945 0.3048)
			(end 0.120396 0.3048)
			(stroke
				(width 0.1)
				(type default)
			)
			(layer "F.Fab")
		)
		(fp_line
			(start 0.67945 -0.3048)
			(end 0.67945 0.3048)
			(stroke
				(width 0.1)
				(type default)
			)
			(layer "F.Fab")
		)
		(fp_line
			(start 0.12065 -0.2794)
			(end 0.12065 -0.3048)
			(stroke
				(width 0.1)
				(type default)
			)
			(layer "F.Fab")
		)
		(fp_line
			(start 0.12065 -0.3048)
			(end 0.67945 -0.3048)
			(stroke
				(width 0.1)
				(type default)
			)
			(layer "F.Fab")
		)
		(fp_line
			(start 0.120396 0.3048)
			(end 0.120396 0.2794)
			(stroke
				(width 0.1)
				(type default)
			)
			(layer "F.Fab")
		)
		(fp_line
			(start 0.120396 0.2794)
			(end -0.12065 0.2794)
			(stroke
				(width 0.1)
				(type default)
			)
			(layer "F.Fab")
		)
		(fp_line
			(start -0.12065 0.3048)
			(end -0.67945 0.3048)
			(stroke
				(width 0.1)
				(type default)
			)
			(layer "F.Fab")
		)
		(fp_line
			(start -0.12065 0.2794)
			(end -0.12065 0.3048)
			(stroke
				(width 0.1)
				(type default)
			)
			(layer "F.Fab")
		)
		(fp_line
			(start -0.12065 -0.2794)
			(end 0.12065 -0.2794)
			(stroke
				(width 0.1)
				(type default)
			)
			(layer "F.Fab")
		)
		(fp_line
			(start -0.12065 -0.305054)
			(end -0.12065 -0.2794)
			(stroke
				(width 0.1)
				(type default)
			)
			(layer "F.Fab")
		)
		(fp_line
			(start -0.67945 0.3048)
			(end -0.67945 -0.305054)
			(stroke
				(width 0.1)
				(type default)
			)
			(layer "F.Fab")
		)
		(fp_line
			(start -0.67945 -0.305054)
			(end -0.12065 -0.305054)
			(stroke
				(width 0.1)
				(type default)
			)
			(layer "F.Fab")
		)
		(pad "1" smd circle
			(at -0.40005 0 180)
			(size 0 0)
			(layers "F.Cu" "F.Mask" "F.Paste")
			(net "FM_9ZXL045_P1_1_OE_N")
		)
		(pad "2" smd circle
			(at 0.40005 0 180)
			(size 0 0)
			(layers "F.Cu" "F.Mask" "F.Paste")
			(net "GND")
		)
	)
)
